# BASEBOARD_FAB2 (Tioga Pass) — schematic netlist excerpt (pin names and nets, part order shuffled) for the footprints in the layout excerpt that follows; sources: Cadence DE-HDL packaged netlist, KiCad conversion of Wiwynn_Tioga_Pass_MB.brd

R9P1  RES  100.0 1% CHIP  pkg 0402  page 206 : A = PVCCIO_CPU1 ; B = SVID_DIO0_CPU1_R
C8M4  CAP_A  47UF 4V 20% X5R  pkg 0603V  page 228 : A = PVDDQ_KLM ; B = GND
C32W2  CAP_A  0.1UF 16V 10% X7R  pkg 0402V  page 185 : A = P3V3_STBY ; B = GND

(kicad_pcb
	(version 20260206)
	(generator "pcbnew")
	(generator_version "10.0")
	(general
		(thickness 1.6)
		(legacy_teardrops no)
	)
	(paper "A4")
	(title_block
		(title "Wiwynn_Tioga_Pass_MB.brd")
		(comment 1 "Tioga Pass / footprints 4572-4574 of 4770")
	)
	(layers
		(0 "F.Cu" signal "TOP")
		(4 "In1.Cu" signal "L2GND")
		(6 "In2.Cu" signal "L3")
		(8 "In3.Cu" signal "L4GND")
		(10 "In4.Cu" signal "L5")
		(12 "In5.Cu" signal "L6GND")
		(14 "In6.Cu" signal "L7VCC")
		(16 "In7.Cu" signal "L8VCC")
		(18 "In8.Cu" signal "L9GND")
		(20 "In9.Cu" signal "L10")
		(22 "In10.Cu" signal "L11GND")
		(24 "In11.Cu" signal "L12")
		(26 "In12.Cu" signal "L13GND")
		(2 "B.Cu" signal "BOTTOM")
		(9 "F.Adhes" user "F.Adhesive")
		(11 "B.Adhes" user "B.Adhesive")
		(13 "F.Paste" user "Package Geometry/Pastemask Top")
		(15 "B.Paste" user "Package Geometry/Pastemask Bottom")
		(5 "F.SilkS" user "Ref Des/Silkscreen Top")
		(7 "B.SilkS" user "Ref Des/Silkscreen Bottom")
		(1 "F.Mask" user "Board Geometry/Soldermask Top")
		(3 "B.Mask" user "Board Geometry/Soldermask Bottom")
		(17 "Dwgs.User" user "User.Drawings")
		(19 "Cmts.User" user "User.Comments")
		(21 "Eco1.User" user "User.Eco1")
		(23 "Eco2.User" user "User.Eco2")
		(25 "Edge.Cuts" user "Board Geometry/Outline")
		(27 "Margin" user)
		(31 "F.CrtYd" user "Package Geometry/Place Bound Top")
		(29 "B.CrtYd" user "Package Geometry/Place Bound Bottom")
		(35 "F.Fab" user "Ref Des/Assembly Top")
		(33 "B.Fab" user "Ref Des/Assembly Bottom")
	)
	(footprint ""
		(layer "B.Cu")
		(at 390.144 -16.383 -90)
		(property "Reference" "C32W2"
			(at 0.8382 -0.67818 270)
			(unlocked yes)
			(layer "B.SilkS")
			(effects
				(font
					(size 0.4064 0.254)
					(thickness 0.1524)
				)
				(justify left mirror)
			)
		)
		(property "Value" ""
			(at 0 0 90)
			(layer "B.Fab")
			(effects
				(font
					(size 1.27 1.27)
				)
				(justify mirror)
			)
		)
		(duplicate_pad_numbers_are_jumpers no)
		(fp_poly
			(pts
				(xy -0.3048 -0.1016) (xy -0.3048 0.9906) (xy 0.3048 0.9906) (xy 0.3048 -0.1016)
			)
			(stroke
				(width 0)
				(type default)
			)
			(fill no)
			(layer "B.CrtYd")
		)
		(fp_line
			(start -0.3048 0.9906)
			(end -0.3048 -0.1016)
			(stroke
				(width 0.1)
				(type default)
			)
			(layer "B.Fab")
		)
		(fp_line
			(start 0.3048 0.9906)
			(end -0.3048 0.9906)
			(stroke
				(width 0.1)
				(type default)
			)
			(layer "B.Fab")
		)
		(fp_line
			(start -0.3048 -0.1016)
			(end 0.3048 -0.1016)
			(stroke
				(width 0.1)
				(type default)
			)
			(layer "B.Fab")
		)
		(fp_line
			(start 0.3048 -0.1016)
			(end 0.3048 0.9906)
			(stroke
				(width 0.1)
				(type default)
			)
			(layer "B.Fab")
		)
		(pad "1" smd rect
			(at 0 0 90)
			(size 0.508 0.508)
			(layers "B.Cu" "B.Mask" "B.Paste")
			(net "P3V3_STBY")
		)
		(pad "2" smd rect
			(at 0 0.889 90)
			(size 0.508 0.508)
			(layers "B.Cu" "B.Mask" "B.Paste")
			(net "GND")
		)
		(zone
			(layer "B.Cu")
			(hatch none 0.5)
			(connect_pads
				(clearance 0)
			)
			(min_thickness 0.25)
			(keepout
				(tracks not_allowed)
				(vias allowed)
				(pads allowed)
				(copperpour not_allowed)
				(footprints allowed)
			)
			(placement
				(enabled no)
				(sheetname "")
			)
			(fill
				(thermal_gap 0.5)
				(thermal_bridge_width 0.5)
				(island_removal_mode 0)
			)
			(polygon
				(pts
					(xy 389.509 -16.129) (xy 389.509 -16.637) (xy 389.89 -16.637) (xy 389.89 -16.129)
				)
			)
		)
		(zone
			(layer "B.Cu")
			(hatch none 0.5)
			(connect_pads
				(clearance 0)
			)
			(min_thickness 0.25)
			(keepout
				(tracks allowed)
				(vias not_allowed)
				(pads allowed)
				(copperpour not_allowed)
				(footprints allowed)
			)
			(placement
				(enabled no)
				(sheetname "")
			)
			(fill
				(thermal_gap 0.5)
				(thermal_bridge_width 0.5)
				(island_removal_mode 0)
			)
			(polygon
				(pts
					(xy 389.89 -16.129) (xy 389.89 -16.637) (xy 389.509 -16.637) (xy 389.509 -16.129)
				)
			)
		)
	)
	(footprint ""
		(layer "B.Cu")
		(at 87.158068 -135.4074 -90)
		(property "Reference" "C8M4"
			(at -1.848866 0.752348 270)
			(unlocked yes)
			(layer "B.SilkS")
			(effects
				(font
					(size 1.27 0.9652)
					(thickness 0.1524)
				)
				(justify mirror)
			)
		)
		(property "Value" ""
			(at 0 0 90)
			(layer "B.Fab")
			(effects
				(font
					(size 1.27 1.27)
				)
				(justify mirror)
			)
		)
		(duplicate_pad_numbers_are_jumpers no)
		(fp_rect
			(start 0.500126 1.598422)
			(end -0.500126 -0.201422)
			(stroke
				(width 0)
				(type default)
			)
			(fill no)
			(layer "B.CrtYd")
		)
		(fp_line
			(start -0.500126 1.598422)
			(end 0.500126 1.598422)
			(stroke
				(width 0.1)
				(type default)
			)
			(layer "B.Fab")
		)
		(fp_line
			(start 0.500126 1.598422)
			(end 0.500126 -0.201422)
			(stroke
				(width 0.1)
				(type default)
			)
			(layer "B.Fab")
		)
		(fp_line
			(start -0.500126 -0.201422)
			(end -0.500126 1.598422)
			(stroke
				(width 0.1)
				(type default)
			)
			(layer "B.Fab")
		)
		(fp_line
			(start 0.500126 -0.201422)
			(end -0.500126 -0.201422)
			(stroke
				(width 0.1)
				(type default)
			)
			(layer "B.Fab")
		)
		(pad "1" smd rect
			(at 0 0 180)
			(size 0.889 0.9906)
			(layers "B.Cu" "B.Mask" "B.Paste")
			(net "PVDDQ_KLM")
		)
		(pad "2" smd rect
			(at 0 1.397 180)
			(size 0.889 0.9906)
			(layers "B.Cu" "B.Mask" "B.Paste")
			(net "GND")
		)
		(zone
			(layer "B.Cu")
			(hatch none 0.5)
			(connect_pads
				(clearance 0)
			)
			(min_thickness 0.25)
			(keepout
				(tracks allowed)
				(vias not_allowed)
				(pads allowed)
				(copperpour not_allowed)
				(footprints allowed)
			)
			(placement
				(enabled no)
				(sheetname "")
			)
			(fill
				(thermal_gap 0.5)
				(thermal_bridge_width 0.5)
				(island_removal_mode 0)
			)
			(polygon
				(pts
					(xy 86.205568 -134.9121) (xy 86.713568 -134.9121) (xy 86.713568 -135.9027) (xy 86.205568 -135.9027)
				)
			)
		)
		(zone
			(layer "B.Cu")
			(hatch none 0.5)
			(connect_pads
				(clearance 0)
			)
			(min_thickness 0.25)
			(keepout
				(tracks not_allowed)
				(vias allowed)
				(pads allowed)
				(copperpour not_allowed)
				(footprints allowed)
			)
			(placement
				(enabled no)
				(sheetname "")
			)
			(fill
				(thermal_gap 0.5)
				(thermal_bridge_width 0.5)
				(island_removal_mode 0)
			)
			(polygon
				(pts
					(xy 86.205568 -134.9121) (xy 86.713568 -134.9121) (xy 86.713568 -135.9027) (xy 86.205568 -135.9027)
				)
			)
		)
	)
	(footprint ""
		(layer "B.Cu")
		(at 18.288 -87.7062)
		(property "Reference" "R9P1"
			(at 0 0 0)
			(layer "B.SilkS")
			(hide yes)
			(effects
				(font
					(size 1.27 1.27)
				)
				(justify mirror)
			)
		)
		(property "Value" ""
			(at 0 0 0)
			(layer "B.Fab")
			(effects
				(font
					(size 1.27 1.27)
				)
				(justify mirror)
			)
		)
		(duplicate_pad_numbers_are_jumpers no)
		(fp_poly
			(pts
				(xy 0.2794 -0.1016) (xy -0.2794 -0.1016) (xy -0.2794 0.9906) (xy 0.2794 0.9906)
			)
			(stroke
				(width 0)
				(type default)
			)
			(fill no)
			(layer "B.CrtYd")
		)
		(fp_line
			(start -0.2794 -0.1016)
			(end 0.2794 -0.1016)
			(stroke
				(width 0.1)
				(type default)
			)
			(layer "B.Fab")
		)
		(fp_line
			(start -0.2794 0.9906)
			(end -0.2794 -0.1016)
			(stroke
				(width 0.1)
				(type default)
			)
			(layer "B.Fab")
		)
		(fp_line
			(start 0.2794 -0.1016)
			(end 0.2794 0.9906)
			(stroke
				(width 0.1)
				(type default)
			)
			(layer "B.Fab")
		)
		(fp_line
			(start 0.2794 0.9906)
			(end -0.2794 0.9906)
			(stroke
				(width 0.1)
				(type default)
			)
			(layer "B.Fab")
		)
		(pad "1" smd rect
			(at 0 0 180)
			(size 0.508 0.508)
			(layers "B.Cu" "B.Mask" "B.Paste")
			(net "PVCCIO_CPU1")
		)
		(pad "2" smd rect
			(at 0 0.889 180)
			(size 0.508 0.508)
			(layers "B.Cu" "B.Mask" "B.Paste")
			(net "SVID_DIO0_CPU1_R")
		)
		(zone
			(layer "B.Cu")
			(hatch none 0.5)
			(connect_pads
				(clearance 0)
			)
			(min_thickness 0.25)
			(keepout
				(tracks allowed)
				(vias not_allowed)
				(pads allowed)
				(copperpour not_allowed)
				(footprints allowed)
			)
			(placement
				(enabled no)
				(sheetname "")
			)
			(fill
				(thermal_gap 0.5)
				(thermal_bridge_width 0.5)
				(island_removal_mode 0)
			)
			(polygon
				(pts
					(xy 18.542 -87.4522) (xy 18.034 -87.4522) (xy 18.034 -87.0712) (xy 18.542 -87.0712)
				)
			)
		)
		(zone
			(layer "B.Cu")
			(hatch none 0.5)
			(connect_pads
				(clearance 0)
			)
			(min_thickness 0.25)
			(keepout
				(tracks not_allowed)
				(vias allowed)
				(pads allowed)
				(copperpour not_allowed)
				(footprints allowed)
			)
			(placement
				(enabled no)
				(sheetname "")
			)
			(fill
				(thermal_gap 0.5)
				(thermal_bridge_width 0.5)
				(island_removal_mode 0)
			)
			(polygon
				(pts
					(xy 18.542 -87.0712) (xy 18.034 -87.0712) (xy 18.034 -87.4522) (xy 18.542 -87.4522)
				)
			)
		)
	)
)
